# TIMECARD (Time Appliance Project (Time Card)) — schematic netlist excerpt (pin names and nets, part order shuffled) for the footprints in the layout excerpt that follows; sources: Cadence DE-HDL packaged netlist, KiCad conversion of R4006-B0001-02_R01.brd

C242  CAPACITOR  0.1UF 25V 10%  pkg SMC_0402R_H022  page 31 : \1\ = XP2R5V_FPGA ; \2\ = SG
C228  CAPACITOR  10UF 25V 20%  pkg SMC_0805R_H057  page 31 : \1\ = UNNAMED_515_CAPACITOR_I130_1 ; \2\ = SG

(kicad_pcb
	(version 20260206)
	(generator "pcbnew")
	(generator_version "10.0")
	(general
		(thickness 1.6)
		(legacy_teardrops no)
	)
	(paper "A4")
	(title_block
		(title "timecard-production-celestica-r4006 — R4006-B0001-02_R01.brd")
		(comment 1 "Time Appliance Project (Time Card) / footprints 302-303 of 1113")
	)
	(layers
		(0 "F.Cu" signal "TOP")
		(4 "In1.Cu" signal "L02_GND1")
		(6 "In2.Cu" signal "L03_SIG1")
		(8 "In3.Cu" signal "L04_GND2")
		(10 "In4.Cu" signal "L05_VCC1")
		(12 "In5.Cu" signal "L06_VCC2")
		(14 "In6.Cu" signal "L07_GND3")
		(16 "In7.Cu" signal "L08_SIG2")
		(18 "In8.Cu" signal "L09_GND4")
		(2 "B.Cu" signal "BOTTOM")
		(9 "F.Adhes" user "F.Adhesive")
		(11 "B.Adhes" user "B.Adhesive")
		(13 "F.Paste" user "Package Geometry/Pastemask Top")
		(15 "B.Paste" user "Package Geometry/Pastemask Bottom")
		(5 "F.SilkS" user "Ref Des/Silkscreen Top")
		(7 "B.SilkS" user "Ref Des/Silkscreen Bottom")
		(1 "F.Mask" user "Board Geometry/Soldermask Top")
		(3 "B.Mask" user "Board Geometry/Soldermask Bottom")
		(17 "Dwgs.User" user "User.Drawings")
		(19 "Cmts.User" user "User.Comments")
		(21 "Eco1.User" user "User.Eco1")
		(23 "Eco2.User" user "User.Eco2")
		(25 "Edge.Cuts" user "Board Geometry/Outline")
		(27 "Margin" user)
		(31 "F.CrtYd" user "Package Geometry/Place Bound Top")
		(29 "B.CrtYd" user "Package Geometry/Place Bound Bottom")
		(35 "F.Fab" user "Ref Des/Assembly Top")
		(33 "B.Fab" user "Ref Des/Assembly Bottom")
	)
	(footprint ""
		(layer "F.Cu")
		(at 140.9192 -20.1168)
		(property "Reference" "C242"
			(at -3.8862 -1.30683 0)
			(unlocked yes)
			(layer "F.SilkS")
			(effects
				(font
					(size 0.7874 0.5842)
					(thickness 0.1524)
				)
			)
		)
		(property "Value" "VAL*"
			(at 0.0762 2.067306 0)
			(unlocked yes)
			(layer "F.Fab")
			(hide yes)
			(effects
				(font
					(size 0.7874 0.5842)
					(thickness 0.1524)
				)
			)
		)
		(property "Tolerance" "TOL*"
			(at 0.0762 3.032506 0)
			(unlocked yes)
			(layer "Cmts.User")
			(hide yes)
			(effects
				(font
					(size 0.7874 0.5842)
					(thickness 0.1524)
				)
			)
		)
		(property "User Part Number" "PARTNUM*"
			(at 0.1016 4.023106 0)
			(unlocked yes)
			(layer "Cmts.User")
			(hide yes)
			(effects
				(font
					(size 0.7874 0.5842)
					(thickness 0.1524)
				)
			)
		)
		(property "Device Type" "CAPACITOR-G105-0B104-EK,0.1UF,A"
			(at 0.0508 1.127506 0)
			(unlocked yes)
			(layer "F.Fab")
			(hide yes)
			(effects
				(font
					(size 0.7874 0.5842)
					(thickness 0.1524)
				)
			)
		)
		(duplicate_pad_numbers_are_jumpers no)
		(fp_line
			(start -1.143 -0.5588)
			(end -1.143 0.5588)
			(stroke
				(width 0.1)
				(type default)
			)
			(layer "F.SilkS")
		)
		(fp_line
			(start -1.143 0.5588)
			(end 1.143 0.5588)
			(stroke
				(width 0.1)
				(type default)
			)
			(layer "F.SilkS")
		)
		(fp_line
			(start 1.143 -0.5588)
			(end -1.143 -0.5588)
			(stroke
				(width 0.1)
				(type default)
			)
			(layer "F.SilkS")
		)
		(fp_line
			(start 1.143 0.5588)
			(end 1.143 -0.5588)
			(stroke
				(width 0.1)
				(type default)
			)
			(layer "F.SilkS")
		)
		(fp_rect
			(start 1.143 -0.5588)
			(end -1.143 0.5588)
			(stroke
				(width 0)
				(type default)
			)
			(fill no)
			(layer "F.CrtYd")
		)
		(fp_line
			(start -0.508 -0.3048)
			(end -0.508 0.3048)
			(stroke
				(width 0.1)
				(type default)
			)
			(layer "F.Fab")
		)
		(fp_line
			(start -0.508 0.3048)
			(end 0.508 0.3048)
			(stroke
				(width 0.1)
				(type default)
			)
			(layer "F.Fab")
		)
		(fp_line
			(start 0.508 -0.3048)
			(end -0.508 -0.3048)
			(stroke
				(width 0.1)
				(type default)
			)
			(layer "F.Fab")
		)
		(fp_line
			(start 0.508 0.3048)
			(end 0.508 -0.3048)
			(stroke
				(width 0.1)
				(type default)
			)
			(layer "F.Fab")
		)
		(pad "1" smd rect
			(at -0.5334 0)
			(size 0.7112 0.6096)
			(layers "F.Cu" "F.Mask" "F.Paste")
			(net "XP2R5V_FPGA")
		)
		(pad "2" smd rect
			(at 0.5334 0)
			(size 0.7112 0.6096)
			(layers "F.Cu" "F.Mask" "F.Paste")
			(net "SG")
		)
		(zone
			(layer "F.Cu")
			(hatch none 0.5)
			(connect_pads
				(clearance 0)
			)
			(min_thickness 0.25)
			(keepout
				(tracks allowed)
				(vias not_allowed)
				(pads allowed)
				(copperpour not_allowed)
				(footprints allowed)
			)
			(placement
				(enabled no)
				(sheetname "")
			)
			(fill
				(thermal_gap 0.5)
				(thermal_bridge_width 0.5)
				(island_removal_mode 0)
			)
			(polygon
				(pts
					(xy 140.9954 -20.4216) (xy 140.843 -20.4216) (xy 140.843 -19.812) (xy 140.9954 -19.812)
				)
			)
		)
	)
	(footprint ""
		(layer "F.Cu")
		(at 143.891 -21.8186 180)
		(property "Reference" "C228"
			(at -3.175 0.74803 0)
			(unlocked yes)
			(layer "F.SilkS")
			(effects
				(font
					(size 0.7874 0.5842)
					(thickness 0.1524)
				)
			)
		)
		(property "Value" "VAL*"
			(at 0.0762 3.134106 180)
			(unlocked yes)
			(layer "F.Fab")
			(hide yes)
			(effects
				(font
					(size 0.7874 0.5842)
					(thickness 0.1524)
				)
			)
		)
		(property "Tolerance" "TOL*"
			(at 0.0762 4.048506 180)
			(unlocked yes)
			(layer "Cmts.User")
			(hide yes)
			(effects
				(font
					(size 0.7874 0.5842)
					(thickness 0.1524)
				)
			)
		)
		(property "User Part Number" "PARTNUM*"
			(at 0.1016 5.013706 180)
			(unlocked yes)
			(layer "Cmts.User")
			(hide yes)
			(effects
				(font
					(size 0.7874 0.5842)
					(thickness 0.1524)
				)
			)
		)
		(property "Device Type" "CAPACITOR-G107-0F106-EM,10UF,2A"
			(at 0.0508 2.194306 180)
			(unlocked yes)
			(layer "F.Fab")
			(hide yes)
			(effects
				(font
					(size 0.7874 0.5842)
					(thickness 0.1524)
				)
			)
		)
		(duplicate_pad_numbers_are_jumpers no)
		(fp_line
			(start 1.5748 0.9398)
			(end 1.5748 -0.9398)
			(stroke
				(width 0.1)
				(type default)
			)
			(layer "F.SilkS")
		)
		(fp_line
			(start 1.5748 -0.9398)
			(end -1.5748 -0.9398)
			(stroke
				(width 0.1)
				(type default)
			)
			(layer "F.SilkS")
		)
		(fp_line
			(start -1.5748 0.9398)
			(end 1.5748 0.9398)
			(stroke
				(width 0.1)
				(type default)
			)
			(layer "F.SilkS")
		)
		(fp_line
			(start -1.5748 -0.9398)
			(end -1.5748 0.9398)
			(stroke
				(width 0.1)
				(type default)
			)
			(layer "F.SilkS")
		)
		(fp_rect
			(start -1.5748 0.9398)
			(end 1.5748 -0.9398)
			(stroke
				(width 0)
				(type default)
			)
			(fill no)
			(layer "F.CrtYd")
		)
		(fp_line
			(start 1.016 0.635)
			(end 1.016 -0.635)
			(stroke
				(width 0.1)
				(type default)
			)
			(layer "F.Fab")
		)
		(fp_line
			(start 1.016 -0.635)
			(end -1.016 -0.635)
			(stroke
				(width 0.1)
				(type default)
			)
			(layer "F.Fab")
		)
		(fp_line
			(start -1.016 0.635)
			(end 1.016 0.635)
			(stroke
				(width 0.1)
				(type default)
			)
			(layer "F.Fab")
		)
		(fp_line
			(start -1.016 -0.635)
			(end -1.016 0.635)
			(stroke
				(width 0.1)
				(type default)
			)
			(layer "F.Fab")
		)
		(pad "1" smd rect
			(at -0.8382 0 180)
			(size 0.9652 1.3716)
			(layers "F.Cu" "F.Mask" "F.Paste")
			(net "UNNAMED_515_CAPACITOR_I130_1")
		)
		(pad "2" smd rect
			(at 0.8382 0 180)
			(size 0.9652 1.3716)
			(layers "F.Cu" "F.Mask" "F.Paste")
			(net "SG")
		)
		(zone
			(layer "F.Cu")
			(hatch none 0.5)
			(connect_pads
				(clearance 0)
			)
			(min_thickness 0.25)
			(keepout
				(tracks allowed)
				(vias not_allowed)
				(pads allowed)
				(copperpour not_allowed)
				(footprints allowed)
			)
			(placement
				(enabled no)
				(sheetname "")
			)
			(fill
				(thermal_gap 0.5)
				(thermal_bridge_width 0.5)
				(island_removal_mode 0)
			)
			(polygon
				(pts
					(xy 144.1196 -22.4536) (xy 143.6624 -22.4536) (xy 143.6624 -21.1836) (xy 144.1196 -21.1836)
				)
			)
		)
	)
)
